# S9S_MB_2U (Grand Teton) — schematic netlist excerpt (pin names and nets, part order shuffled) for the footprints in the layout excerpt that follows; sources: Cadence DE-HDL packaged netlist, KiCad conversion of 03242023_DA0F0TMBIJ0_F0T_Motherboard_J_brd_V01_OCP.brd

U50  74LVC1G08W57  74LVC1G08W5-7 IC  pkg SOT25-5_0-95_3X1-6  page 164
  A  = HP_OCP_V3_2_EN
  B  = HP_LVC3_OCP_V3_2_PRSNT2
  GND  = GND
  Y  = HP_LVC3_OCP_V3_2_EN
  VCC  = P3V3_AUX

R4656  Q_RES  1K 1% CHIP  pkg 0402LF  page 167 : A = P3V3_AUX ; B = FM_P2E_BUF2_SD_TH

(kicad_pcb
	(version 20260206)
	(generator "pcbnew")
	(generator_version "10.0")
	(general
		(thickness 1.6)
		(legacy_teardrops no)
	)
	(paper "A4")
	(title_block
		(title "03242023_DA0F0TMBIJ0_F0T_Motherboard_J_brd_V01_OCP.brd")
		(comment 1 "Grand Teton / footprints 1915-1916 of 6105")
	)
	(layers
		(0 "F.Cu" signal "TOP")
		(4 "In1.Cu" signal "GND")
		(6 "In2.Cu" signal "IN1")
		(8 "In3.Cu" signal "GND1")
		(10 "In4.Cu" signal "IN2")
		(12 "In5.Cu" signal "GND2")
		(14 "In6.Cu" signal "IN3")
		(16 "In7.Cu" signal "GND3")
		(18 "In8.Cu" signal "VCC")
		(20 "In9.Cu" signal "VCC1")
		(22 "In10.Cu" signal "GND4")
		(24 "In11.Cu" signal "IN4")
		(26 "In12.Cu" signal "GND5")
		(28 "In13.Cu" signal "IN5")
		(30 "In14.Cu" signal "GND6")
		(32 "In15.Cu" signal "IN6")
		(34 "In16.Cu" signal "GND7")
		(2 "B.Cu" signal "BOTTOM")
		(9 "F.Adhes" user "F.Adhesive")
		(11 "B.Adhes" user "B.Adhesive")
		(13 "F.Paste" user "Package Geometry/Pastemask Top")
		(15 "B.Paste" user "Package Geometry/Pastemask Bottom")
		(5 "F.SilkS" user "Ref Des/Silkscreen Top")
		(7 "B.SilkS" user "Ref Des/Silkscreen Bottom")
		(1 "F.Mask" user "Board Geometry/Soldermask Top")
		(3 "B.Mask" user "Board Geometry/Soldermask Bottom")
		(17 "Dwgs.User" user "User.Drawings")
		(19 "Cmts.User" user "User.Comments")
		(21 "Eco1.User" user "User.Eco1")
		(23 "Eco2.User" user "User.Eco2")
		(25 "Edge.Cuts" user "Board Geometry/Outline")
		(27 "Margin" user)
		(31 "F.CrtYd" user "Package Geometry/Place Bound Top")
		(29 "B.CrtYd" user "Package Geometry/Place Bound Bottom")
		(35 "F.Fab" user "Ref Des/Assembly Top")
		(33 "B.Fab" user "Ref Des/Assembly Bottom")
	)
	(footprint ""
		(layer "F.Cu")
		(at 29.948124 -393.198858)
		(property "Reference" "R4656"
			(at 0 0 0)
			(layer "F.SilkS")
			(hide yes)
			(effects
				(font
					(size 1.27 1.27)
				)
			)
		)
		(property "Value" ""
			(at 0 0 0)
			(layer "F.Fab")
			(effects
				(font
					(size 1.27 1.27)
				)
			)
		)
		(duplicate_pad_numbers_are_jumpers no)
		(fp_line
			(start -0.7874 -0.4064)
			(end 0.7874 -0.4064)
			(stroke
				(width 0.1524)
				(type default)
			)
			(layer "F.SilkS")
		)
		(fp_line
			(start -0.7874 0.4064)
			(end -0.7874 -0.4064)
			(stroke
				(width 0.1524)
				(type default)
			)
			(layer "F.SilkS")
		)
		(fp_line
			(start 0.7874 -0.4064)
			(end 0.7874 0.4064)
			(stroke
				(width 0.1524)
				(type default)
			)
			(layer "F.SilkS")
		)
		(fp_line
			(start 0.7874 0.4064)
			(end -0.7874 0.4064)
			(stroke
				(width 0.1524)
				(type default)
			)
			(layer "F.SilkS")
		)
		(fp_line
			(start -0.67945 -0.305054)
			(end -0.12065 -0.305054)
			(stroke
				(width 0.1)
				(type default)
			)
			(layer "F.Fab")
		)
		(fp_line
			(start -0.67945 0.3048)
			(end -0.67945 -0.305054)
			(stroke
				(width 0.1)
				(type default)
			)
			(layer "F.Fab")
		)
		(fp_line
			(start -0.12065 -0.305054)
			(end -0.12065 -0.2794)
			(stroke
				(width 0.1)
				(type default)
			)
			(layer "F.Fab")
		)
		(fp_line
			(start -0.12065 -0.2794)
			(end 0.12065 -0.2794)
			(stroke
				(width 0.1)
				(type default)
			)
			(layer "F.Fab")
		)
		(fp_line
			(start -0.12065 0.2794)
			(end -0.12065 0.3048)
			(stroke
				(width 0.1)
				(type default)
			)
			(layer "F.Fab")
		)
		(fp_line
			(start -0.12065 0.3048)
			(end -0.67945 0.3048)
			(stroke
				(width 0.1)
				(type default)
			)
			(layer "F.Fab")
		)
		(fp_line
			(start 0.120396 0.2794)
			(end -0.12065 0.2794)
			(stroke
				(width 0.1)
				(type default)
			)
			(layer "F.Fab")
		)
		(fp_line
			(start 0.120396 0.3048)
			(end 0.120396 0.2794)
			(stroke
				(width 0.1)
				(type default)
			)
			(layer "F.Fab")
		)
		(fp_line
			(start 0.12065 -0.3048)
			(end 0.67945 -0.3048)
			(stroke
				(width 0.1)
				(type default)
			)
			(layer "F.Fab")
		)
		(fp_line
			(start 0.12065 -0.2794)
			(end 0.12065 -0.3048)
			(stroke
				(width 0.1)
				(type default)
			)
			(layer "F.Fab")
		)
		(fp_line
			(start 0.67945 -0.3048)
			(end 0.67945 0.3048)
			(stroke
				(width 0.1)
				(type default)
			)
			(layer "F.Fab")
		)
		(fp_line
			(start 0.67945 0.3048)
			(end 0.120396 0.3048)
			(stroke
				(width 0.1)
				(type default)
			)
			(layer "F.Fab")
		)
		(pad "1" smd circle
			(at -0.40005 0)
			(size 0 0)
			(layers "F.Cu" "F.Mask" "F.Paste")
			(net "P3V3_AUX")
		)
		(pad "2" smd circle
			(at 0.40005 0)
			(size 0 0)
			(layers "F.Cu" "F.Mask" "F.Paste")
			(net "FM_P2E_BUF2_SD_TH")
		)
	)
	(footprint ""
		(layer "F.Cu")
		(at 131.364736 -118.226078 -90)
		(property "Reference" "U50"
			(at 1.24968 -2.246884 0)
			(unlocked yes)
			(layer "F.SilkS")
			(effects
				(font
					(size 0.7874 0.5842)
					(thickness 0.1524)
				)
				(justify left)
			)
		)
		(property "Value" ""
			(at 0 0 270)
			(layer "F.Fab")
			(effects
				(font
					(size 1.27 1.27)
				)
			)
		)
		(duplicate_pad_numbers_are_jumpers no)
		(fp_line
			(start -1.733296 1.549908)
			(end 1.733296 1.549908)
			(stroke
				(width 0.1524)
				(type default)
			)
			(layer "F.SilkS")
		)
		(fp_line
			(start 1.733296 1.549908)
			(end 1.733296 -1.549908)
			(stroke
				(width 0.1524)
				(type default)
			)
			(layer "F.SilkS")
		)
		(fp_line
			(start 0 -0.889)
			(end -0.660908 -1.549908)
			(stroke
				(width 0.1524)
				(type default)
			)
			(layer "F.SilkS")
		)
		(fp_line
			(start -1.733296 -1.549908)
			(end -1.733296 1.549908)
			(stroke
				(width 0.1524)
				(type default)
			)
			(layer "F.SilkS")
		)
		(fp_line
			(start -0.660908 -1.549908)
			(end -1.733296 -1.549908)
			(stroke
				(width 0.1524)
				(type default)
			)
			(layer "F.SilkS")
		)
		(fp_line
			(start 0.660908 -1.549908)
			(end 0 -0.889)
			(stroke
				(width 0.1524)
				(type default)
			)
			(layer "F.SilkS")
		)
		(fp_line
			(start 1.733296 -1.549908)
			(end 0.660908 -1.549908)
			(stroke
				(width 0.1524)
				(type default)
			)
			(layer "F.SilkS")
		)
		(fp_poly
			(pts
				(xy -2.41046 -1.18618) (xy -1.90246 -0.93218) (xy -2.41046 -0.67818)
			)
			(stroke
				(width 0)
				(type default)
			)
			(fill yes)
			(layer "F.SilkS")
		)
		(fp_line
			(start -0.849884 1.549908)
			(end 0.849884 1.549908)
			(stroke
				(width 0.1)
				(type default)
			)
			(layer "F.Fab")
		)
		(fp_line
			(start 0.849884 1.549908)
			(end 0.849884 -1.549908)
			(stroke
				(width 0.1)
				(type default)
			)
			(layer "F.Fab")
		)
		(fp_line
			(start -0.849884 -1.549908)
			(end -0.849884 1.549908)
			(stroke
				(width 0.1)
				(type default)
			)
			(layer "F.Fab")
		)
		(fp_line
			(start 0.849884 -1.549908)
			(end -0.849884 -1.549908)
			(stroke
				(width 0.1)
				(type default)
			)
			(layer "F.Fab")
		)
		(fp_poly
			(pts
				(xy -2.4384 -1.20396) (xy -2.4384 -0.69596) (xy -1.9304 -0.94996)
			)
			(stroke
				(width 0)
				(type default)
			)
			(fill yes)
			(layer "F.Fab")
		)
		(pad "1" smd rect
			(at -1.199896 -0.94996 180)
			(size 0.5588 0.8128)
			(layers "F.Cu" "F.Mask" "F.Paste")
			(net "HP_OCP_V3_2_EN")
		)
		(pad "2" smd rect
			(at -1.199896 0 180)
			(size 0.5588 0.8128)
			(layers "F.Cu" "F.Mask" "F.Paste")
			(net "HP_LVC3_OCP_V3_2_PRSNT2")
		)
		(pad "3" smd rect
			(at -1.199896 0.94996 180)
			(size 0.5588 0.8128)
			(layers "F.Cu" "F.Mask" "F.Paste")
			(net "GND")
		)
		(pad "4" smd rect
			(at 1.199896 0.94996 180)
			(size 0.5588 0.8128)
			(layers "F.Cu" "F.Mask" "F.Paste")
			(net "HP_LVC3_OCP_V3_2_EN")
		)
		(pad "5" smd rect
			(at 1.199896 -0.94996 180)
			(size 0.5588 0.8128)
			(layers "F.Cu" "F.Mask" "F.Paste")
			(net "P3V3_AUX")
		)
	)
)
